#ISCELL
  cls sheet_a1 *
  *
#ISCELL
  cls offpage_in *
  page7_i1
#CELL
  passive resistor *
  page7_i13
#CELL
  passive resistor *
  page7_i14
#ISCELL
  cls vcc *
  page7_i15
#ISCELL
  cls vcc *
  page7_i17
#CELL
  passive capacitor *
  page7_i18
#CELL
  passive capacitor *
  page7_i19
#ISCELL
  cls offpage_bi *
  page7_i2
#ISCELL
  cls vcc *
  page7_i20
#CELL
  passive ferritebead *
  page7_i21
#ISCELL
  cls gnd_sg *
  page7_i22
#CELL
  passive capacitor *
  page7_i23
#ISCELL
  cls gnd_sg *
  page7_i25
#CELL
  passive resistor *
  page7_i3
#ISCELL
  cls offpage_in *
  page7_i32
#CELL
  passive resistor *
  page7_i33
#ISCELL
  cls gnd_sg *
  page7_i36
#ISCELL
  cls vcc *
  page7_i37
#CELL
  passive resistor *
  page7_i38
#CELL
  passive resistor *
  page7_i39
#CELL
  passive resistor *
  page7_i4
#CELL
  passive resistor *
  page7_i40
#CELL
  passive resistor *
  page7_i41
#ISCELL
  cls vcc *
  page7_i42
#ISCELL
  cls offpage_out *
  page7_i43
#CELL
  analog sht31a_dis_b10ks_dfn8 *
  page7_i44
#ISCELL
  cls offpage_in *
  page7_i45
#ISCELL
  cls offpage_out *
  page7_i46
#ISCELL
  cls gnd_sg *
  page7_i6
#CELL
  passive resistor *
  page7_i7
#CELL
  passive resistor *
  page7_i8
